FILE_TYPE = MACRO_DRAWING;
SET COLOR_WIRE YELLOW;
SET COLOR_PROP MONO;
SET COLOR_DOT WHITE;
SET COLOR_ARC YELLOW;
SET COLOR_BODY GREEN;
SET COLOR_NOTE MONO;
SET PROP_DISPLAY VALUE;
SET PAGE_NUMBER P110;
FORCEADD RCC_DFX1940..1
(-425 1350);
FORCEPROP 2 LASTPIN (-625 1350) $PN 1
J 2
(-635 1360);
DISPLAY 0.617021 (-635 1360);
PAINT ORANGE (-635 1360);
FORCEPROP 1 LAST LOCATION TC9F1
J 0
(-575 1475);
DISPLAY 0.617021 (-575 1475);
PAINT AQUA (-575 1475);
FORCEPROP 1 LAST PACK_TYPE ID4
J 0
(-575 1425);
DISPLAY 0.617021 (-575 1425);
PAINT SKYBLUE (-575 1425);
FORCEPROP 1 LAST MATERIAL EMPTY
J 0
(-425 1500);
DISPLAY 0.617021 (-425 1500);
PAINT RED (-425 1500);
FORCEPROP 2 LASTPIN (-325 1300) $PN 3
J 0
(-315 1310);
DISPLAY 0.617021 (-315 1310);
PAINT ORANGE (-315 1310);
FORCEPROP 2 LASTPIN (-325 1400) $PN 2
J 0
(-315 1410);
DISPLAY 0.617021 (-315 1410);
PAINT ORANGE (-315 1410);
FORCEPROP 2 LAST CDS_LOCATION TC9F1
J 0
(-575 1475);
DISPLAY 0.617021 (-575 1475);
PAINT AQUA (-575 1475);
DISPLAY INVISIBLE (-575 1475);
FORCEPROP 1 LAST PART_NUMBER N_A
J 0
(-365 1200);
DISPLAY 1.170213 (-365 1200);
PAINT BLUE (-365 1200);
DISPLAY INVISIBLE (-365 1200);
FORCEPROP 2 LAST CDS_LIB mstr_misc
J 0
(-425 1350);
PAINT ORANGE (-425 1350);
DISPLAY INVISIBLE (-425 1350);
FORCEPROP 1 LAST PATH I1
J 0
(-125 1500);
DISPLAY 0.872340 (-125 1500);
PAINT PINK (-125 1500);
DISPLAY INVISIBLE (-125 1500);
FORCEPROP 2 LAST CDS_SEC 1
J 0
(-125 1550);
DISPLAY 1.361702 (-125 1550);
PAINT ORANGE (-125 1550);
DISPLAY INVISIBLE (-125 1550);
FORCEPROP 2 LAST $SEC 1
J 0
(-125 1550);
DISPLAY 0.914894 (-125 1550);
PAINT MONO (-125 1550);
DISPLAY INVISIBLE (-125 1550);
FORCEADD GND..1
(-2350 750);
FORCEPROP 3 LASTPIN (-2350 800) SIG_NAME GND\g
J 0
(-2340 810);
DISPLAY 0.659574 (-2340 810);
PAINT MONO (-2340 810);
DISPLAY INVISIBLE (-2340 810);
FORCEPROP 1 LAST VOLTAGE 0.0V
J 0
(-2395 707);
DISPLAY 0.340426 (-2395 707);
PAINT SKYBLUE (-2395 707);
DISPLAY INVISIBLE (-2395 707);
FORCEPROP 2 LAST CDS_LIB mstr_symbols
J 0
(-2350 750);
PAINT ORANGE (-2350 750);
DISPLAY INVISIBLE (-2350 750);
FORCEPROP 1 LAST BODY_TYPE PLUMBING
J 0
(-2395 707);
DISPLAY 0.340426 (-2395 707);
PAINT GREEN (-2395 707);
DISPLAY INVISIBLE (-2395 707);
FORCEPROP 1 LAST HDL_POWER GND
J 0
(-2350 900);
DISPLAY 1.170213 (-2350 900);
PAINT GREEN (-2350 900);
DISPLAY INVISIBLE (-2350 900);
FORCEPROP 1 LAST SIZE 1B
J 0
(-2275 700);
DISPLAY 1.170213 (-2275 700);
PAINT AQUA (-2275 700);
DISPLAY INVISIBLE (-2275 700);
FORCEPROP 1 LAST PATH I10
J 0
(-2275 750);
DISPLAY 0.872340 (-2275 750);
PAINT AQUA (-2275 750);
DISPLAY INVISIBLE (-2275 750);
FORCEADD SNLABEL_A..1
(-1525 4450);
FORCEPROP 1 LAST LOCATION LB2F1
J 0
(-1550 4525);
DISPLAY 0.617021 (-1550 4525);
PAINT AQUA (-1550 4525);
FORCEPROP 1 LAST MATERIAL EMPTY
J 0
(-1425 4425);
DISPLAY 0.617021 (-1425 4425);
PAINT RED (-1425 4425);
FORCEPROP 2 LAST CDS_LOCATION LB2F1
J 0
(-1550 4525);
DISPLAY 0.617021 (-1550 4525);
PAINT AQUA (-1550 4525);
DISPLAY INVISIBLE (-1550 4525);
FORCEPROP 2 LAST ROOM LABELS
J 0
(-1550 4575);
DISPLAY 1.361702 (-1550 4575);
PAINT ORANGE (-1550 4575);
DISPLAY INVISIBLE (-1550 4575);
FORCEPROP 1 LAST PART_NUMBER N_A
J 0
(-1550 4625);
DISPLAY 1.319149 (-1550 4625);
PAINT BLUE (-1550 4625);
DISPLAY INVISIBLE (-1550 4625);
FORCEPROP 1 LAST PACK_TYPE LABEL
J 0
(-1550 4625);
DISPLAY 1.319149 (-1550 4625);
PAINT SKYBLUE (-1550 4625);
DISPLAY INVISIBLE (-1550 4625);
FORCEPROP 2 LAST BOM_COST TEST_MFG
J 0
(-1550 4625);
DISPLAY 1.361702 (-1550 4625);
PAINT ORANGE (-1550 4625);
DISPLAY INVISIBLE (-1550 4625);
FORCEPROP 2 LAST CDS_LIB mstr_misc
J 0
(-1525 4450);
PAINT ORANGE (-1525 4450);
DISPLAY INVISIBLE (-1525 4450);
FORCEPROP 1 LAST PATH I11
J 0
(-1425 4475);
DISPLAY 0.872340 (-1425 4475);
PAINT PINK (-1425 4475);
DISPLAY INVISIBLE (-1425 4475);
FORCEADD SNLABEL_A..1
(-1525 3800);
FORCEPROP 1 LAST LOCATION LB5F1
J 0
(-1550 3875);
DISPLAY 0.617021 (-1550 3875);
PAINT AQUA (-1550 3875);
FORCEPROP 1 LAST MATERIAL EMPTY
J 0
(-1425 3775);
DISPLAY 0.617021 (-1425 3775);
PAINT RED (-1425 3775);
FORCEPROP 1 LAST PART_NUMBER N_A
J 0
(-1550 3975);
DISPLAY 1.319149 (-1550 3975);
PAINT BLUE (-1550 3975);
DISPLAY INVISIBLE (-1550 3975);
FORCEPROP 1 LAST PACK_TYPE LABEL
J 0
(-1550 3975);
DISPLAY 1.319149 (-1550 3975);
PAINT SKYBLUE (-1550 3975);
DISPLAY INVISIBLE (-1550 3975);
FORCEPROP 2 LAST BOM_COST TEST_MFG
J 0
(-1550 3975);
DISPLAY 1.361702 (-1550 3975);
PAINT ORANGE (-1550 3975);
DISPLAY INVISIBLE (-1550 3975);
FORCEPROP 2 LAST CDS_LOCATION LB5F1
J 0
(-1550 3875);
DISPLAY 0.617021 (-1550 3875);
PAINT AQUA (-1550 3875);
DISPLAY INVISIBLE (-1550 3875);
FORCEPROP 2 LAST ROOM LABELS
J 0
(-1550 3925);
DISPLAY 1.361702 (-1550 3925);
PAINT ORANGE (-1550 3925);
DISPLAY INVISIBLE (-1550 3925);
FORCEPROP 2 LAST CDS_LIB mstr_misc
J 0
(-1525 3800);
PAINT ORANGE (-1525 3800);
DISPLAY INVISIBLE (-1525 3800);
FORCEPROP 1 LAST PATH I12
J 0
(-1425 3825);
DISPLAY 0.872340 (-1425 3825);
PAINT PINK (-1425 3825);
DISPLAY INVISIBLE (-1425 3825);
FORCEADD SNLABEL_A..1
(-1525 3125);
FORCEPROP 1 LAST LOCATION LB2B1
J 0
(-1550 3200);
DISPLAY 0.617021 (-1550 3200);
PAINT AQUA (-1550 3200);
FORCEPROP 1 LAST MATERIAL EMPTY
J 0
(-1425 3100);
DISPLAY 0.617021 (-1425 3100);
PAINT RED (-1425 3100);
FORCEPROP 2 LAST CDS_LOCATION LB2B1
J 0
(-1550 3200);
DISPLAY 0.617021 (-1550 3200);
PAINT AQUA (-1550 3200);
DISPLAY INVISIBLE (-1550 3200);
FORCEPROP 2 LAST ROOM LABELS
J 0
(-1550 3250);
DISPLAY 1.361702 (-1550 3250);
PAINT ORANGE (-1550 3250);
DISPLAY INVISIBLE (-1550 3250);
FORCEPROP 1 LAST PART_NUMBER N_A
J 0
(-1550 3300);
DISPLAY 1.319149 (-1550 3300);
PAINT BLUE (-1550 3300);
DISPLAY INVISIBLE (-1550 3300);
FORCEPROP 1 LAST PACK_TYPE LABEL
J 0
(-1550 3300);
DISPLAY 1.319149 (-1550 3300);
PAINT SKYBLUE (-1550 3300);
DISPLAY INVISIBLE (-1550 3300);
FORCEPROP 2 LAST BOM_COST TEST_MFG
J 0
(-1550 3300);
DISPLAY 1.361702 (-1550 3300);
PAINT ORANGE (-1550 3300);
DISPLAY INVISIBLE (-1550 3300);
FORCEPROP 2 LAST CDS_LIB mstr_misc
J 0
(-1525 3125);
PAINT ORANGE (-1525 3125);
DISPLAY INVISIBLE (-1525 3125);
FORCEPROP 1 LAST PATH I13
J 0
(-1425 3150);
DISPLAY 0.872340 (-1425 3150);
PAINT PINK (-1425 3150);
DISPLAY INVISIBLE (-1425 3150);
FORCEADD SNLABEL_A..1
(-1500 2425);
FORCEPROP 1 LAST LOCATION LB5B1
J 0
(-1525 2500);
DISPLAY 0.617021 (-1525 2500);
PAINT AQUA (-1525 2500);
FORCEPROP 1 LAST MATERIAL EMPTY
J 0
(-1400 2400);
DISPLAY 0.617021 (-1400 2400);
PAINT RED (-1400 2400);
FORCEPROP 2 LAST CDS_LIB mstr_misc
J 0
(-1500 2425);
PAINT ORANGE (-1500 2425);
DISPLAY INVISIBLE (-1500 2425);
FORCEPROP 2 LAST CDS_LOCATION LB5B1
J 0
(-1525 2500);
DISPLAY 0.617021 (-1525 2500);
PAINT AQUA (-1525 2500);
DISPLAY INVISIBLE (-1525 2500);
FORCEPROP 1 LAST PATH I14
J 0
(-1400 2450);
DISPLAY 0.872340 (-1400 2450);
PAINT PINK (-1400 2450);
DISPLAY INVISIBLE (-1400 2450);
FORCEPROP 2 LAST ROOM LABELS
J 0
(-1525 2550);
DISPLAY 1.361702 (-1525 2550);
PAINT ORANGE (-1525 2550);
DISPLAY INVISIBLE (-1525 2550);
FORCEPROP 1 LAST PART_NUMBER N_A
J 0
(-1525 2600);
DISPLAY 1.319149 (-1525 2600);
PAINT BLUE (-1525 2600);
DISPLAY INVISIBLE (-1525 2600);
FORCEPROP 1 LAST PACK_TYPE LABEL
J 0
(-1525 2600);
DISPLAY 1.319149 (-1525 2600);
PAINT SKYBLUE (-1525 2600);
DISPLAY INVISIBLE (-1525 2600);
FORCEPROP 2 LAST BOM_COST TEST_MFG
J 0
(-1525 2600);
DISPLAY 1.361702 (-1525 2600);
PAINT ORANGE (-1525 2600);
DISPLAY INVISIBLE (-1525 2600);
FORCEADD SNLABEL_A..1
(-1525 1900);
FORCEPROP 1 LAST LOCATION LB6T1
J 0
(-1550 1975);
DISPLAY 0.617021 (-1550 1975);
PAINT AQUA (-1550 1975);
FORCEPROP 1 LAST MATERIAL EMPTY
J 0
(-1425 1875);
DISPLAY 0.617021 (-1425 1875);
PAINT RED (-1425 1875);
FORCEPROP 2 LAST CDS_LOCATION LB6T1
J 0
(-1550 1975);
DISPLAY 0.617021 (-1550 1975);
PAINT AQUA (-1550 1975);
DISPLAY INVISIBLE (-1550 1975);
FORCEPROP 2 LAST CDS_LIB mstr_misc
J 0
(-1525 1900);
PAINT ORANGE (-1525 1900);
DISPLAY INVISIBLE (-1525 1900);
FORCEPROP 1 LAST PATH I15
J 0
(-1425 1925);
DISPLAY 0.872340 (-1425 1925);
PAINT PINK (-1425 1925);
DISPLAY INVISIBLE (-1425 1925);
FORCEPROP 2 LAST ROOM LABELS
J 0
(-1550 2025);
DISPLAY 1.361702 (-1550 2025);
PAINT ORANGE (-1550 2025);
DISPLAY INVISIBLE (-1550 2025);
FORCEPROP 1 LAST PART_NUMBER N_A
J 0
(-1550 2075);
DISPLAY 1.319149 (-1550 2075);
PAINT BLUE (-1550 2075);
DISPLAY INVISIBLE (-1550 2075);
FORCEPROP 1 LAST PACK_TYPE LABEL
J 0
(-1550 2075);
DISPLAY 1.319149 (-1550 2075);
PAINT SKYBLUE (-1550 2075);
DISPLAY INVISIBLE (-1550 2075);
FORCEPROP 2 LAST BOM_COST TEST_MFG
J 0
(-1550 2075);
DISPLAY 1.361702 (-1550 2075);
PAINT ORANGE (-1550 2075);
DISPLAY INVISIBLE (-1550 2075);
FORCEADD GND..1
(-675 1150);
FORCEPROP 3 LASTPIN (-675 1200) SIG_NAME GND\g
J 0
(-665 1210);
DISPLAY 0.659574 (-665 1210);
PAINT MONO (-665 1210);
DISPLAY INVISIBLE (-665 1210);
FORCEPROP 1 LAST VOLTAGE 0.0V
J 0
(-720 1107);
DISPLAY 0.340426 (-720 1107);
PAINT SKYBLUE (-720 1107);
DISPLAY INVISIBLE (-720 1107);
FORCEPROP 1 LAST SIZE 1B
J 0
(-600 1100);
DISPLAY 1.170213 (-600 1100);
PAINT AQUA (-600 1100);
DISPLAY INVISIBLE (-600 1100);
FORCEPROP 2 LAST CDS_LIB mstr_symbols
J 0
(-675 1150);
PAINT ORANGE (-675 1150);
DISPLAY INVISIBLE (-675 1150);
FORCEPROP 1 LAST BODY_TYPE PLUMBING
J 0
(-720 1107);
DISPLAY 0.340426 (-720 1107);
PAINT GREEN (-720 1107);
DISPLAY INVISIBLE (-720 1107);
FORCEPROP 1 LAST PATH I2
J 0
(-600 1150);
DISPLAY 0.872340 (-600 1150);
PAINT AQUA (-600 1150);
DISPLAY INVISIBLE (-600 1150);
FORCEPROP 1 LAST HDL_POWER GND
J 0
(-675 1300);
DISPLAY 1.170213 (-675 1300);
PAINT GREEN (-675 1300);
DISPLAY INVISIBLE (-675 1300);
FORCEADD RCC_DFX1940..1
(-400 925);
FORCEPROP 2 LASTPIN (-600 925) $PN 1
J 2
(-610 935);
DISPLAY 0.617021 (-610 935);
PAINT ORANGE (-610 935);
FORCEPROP 2 LASTPIN (-300 875) $PN 3
J 0
(-290 885);
DISPLAY 0.617021 (-290 885);
PAINT ORANGE (-290 885);
FORCEPROP 2 LASTPIN (-300 975) $PN 2
J 0
(-290 985);
DISPLAY 0.617021 (-290 985);
PAINT ORANGE (-290 985);
FORCEPROP 1 LAST PACK_TYPE ID4
J 0
(-550 1000);
DISPLAY 0.617021 (-550 1000);
PAINT SKYBLUE (-550 1000);
FORCEPROP 1 LAST LOCATION TC1G1
J 0
(-550 1050);
DISPLAY 0.617021 (-550 1050);
PAINT AQUA (-550 1050);
FORCEPROP 1 LAST MATERIAL EMPTY
J 0
(-400 1075);
DISPLAY 0.617021 (-400 1075);
PAINT RED (-400 1075);
FORCEPROP 2 LAST CDS_LIB mstr_misc
J 0
(-400 925);
PAINT ORANGE (-400 925);
DISPLAY INVISIBLE (-400 925);
FORCEPROP 1 LAST PART_NUMBER N_A
J 0
(-340 775);
DISPLAY 1.170213 (-340 775);
PAINT BLUE (-340 775);
DISPLAY INVISIBLE (-340 775);
FORCEPROP 2 LAST CDS_LOCATION TC1G1
J 0
(-550 1050);
DISPLAY 0.617021 (-550 1050);
PAINT AQUA (-550 1050);
DISPLAY INVISIBLE (-550 1050);
FORCEPROP 2 LAST CDS_SEC 1
J 0
(-100 1125);
DISPLAY 1.361702 (-100 1125);
PAINT ORANGE (-100 1125);
DISPLAY INVISIBLE (-100 1125);
FORCEPROP 2 LAST $SEC 1
J 0
(-100 1125);
DISPLAY 0.914894 (-100 1125);
PAINT MONO (-100 1125);
DISPLAY INVISIBLE (-100 1125);
FORCEPROP 1 LAST PATH I3
J 0
(-100 1075);
DISPLAY 0.872340 (-100 1075);
PAINT PINK (-100 1075);
DISPLAY INVISIBLE (-100 1075);
FORCEADD GND..1
(-675 750);
FORCEPROP 3 LASTPIN (-675 800) SIG_NAME GND\g
J 0
(-665 810);
DISPLAY 0.659574 (-665 810);
PAINT MONO (-665 810);
DISPLAY INVISIBLE (-665 810);
FORCEPROP 1 LAST VOLTAGE 0.0V
J 0
(-720 707);
DISPLAY 0.340426 (-720 707);
PAINT SKYBLUE (-720 707);
DISPLAY INVISIBLE (-720 707);
FORCEPROP 1 LAST SIZE 1B
J 0
(-600 700);
DISPLAY 1.170213 (-600 700);
PAINT AQUA (-600 700);
DISPLAY INVISIBLE (-600 700);
FORCEPROP 1 LAST BODY_TYPE PLUMBING
J 0
(-720 707);
DISPLAY 0.340426 (-720 707);
PAINT GREEN (-720 707);
DISPLAY INVISIBLE (-720 707);
FORCEPROP 2 LAST CDS_LIB mstr_symbols
J 0
(-675 750);
PAINT ORANGE (-675 750);
DISPLAY INVISIBLE (-675 750);
FORCEPROP 1 LAST PATH I4
J 0
(-600 750);
DISPLAY 0.872340 (-600 750);
PAINT AQUA (-600 750);
DISPLAY INVISIBLE (-600 750);
FORCEPROP 1 LAST HDL_POWER GND
J 0
(-675 900);
DISPLAY 1.170213 (-675 900);
PAINT GREEN (-675 900);
DISPLAY INVISIBLE (-675 900);
FORCEADD RCC_DFX1940..1
(-2075 1325);
FORCEPROP 2 LASTPIN (-2275 1325) $PN 1
J 2
(-2285 1335);
DISPLAY 0.617021 (-2285 1335);
PAINT ORANGE (-2285 1335);
FORCEPROP 1 LAST LOCATION TC1A1
J 0
(-2225 1450);
DISPLAY 0.617021 (-2225 1450);
PAINT AQUA (-2225 1450);
FORCEPROP 1 LAST PACK_TYPE ID4
J 0
(-2225 1400);
DISPLAY 0.617021 (-2225 1400);
PAINT SKYBLUE (-2225 1400);
FORCEPROP 1 LAST MATERIAL EMPTY
J 0
(-2075 1475);
DISPLAY 0.617021 (-2075 1475);
PAINT RED (-2075 1475);
FORCEPROP 2 LASTPIN (-1975 1275) $PN 3
J 0
(-1965 1285);
DISPLAY 0.617021 (-1965 1285);
PAINT ORANGE (-1965 1285);
FORCEPROP 2 LASTPIN (-1975 1375) $PN 2
J 0
(-1965 1385);
DISPLAY 0.617021 (-1965 1385);
PAINT ORANGE (-1965 1385);
FORCEPROP 2 LAST CDS_LOCATION TC1A1
J 0
(-2225 1450);
DISPLAY 0.617021 (-2225 1450);
PAINT AQUA (-2225 1450);
DISPLAY INVISIBLE (-2225 1450);
FORCEPROP 2 LAST CDS_LIB mstr_misc
J 0
(-2075 1325);
PAINT ORANGE (-2075 1325);
DISPLAY INVISIBLE (-2075 1325);
FORCEPROP 1 LAST PART_NUMBER N_A
J 0
(-2015 1175);
DISPLAY 1.170213 (-2015 1175);
PAINT BLUE (-2015 1175);
DISPLAY INVISIBLE (-2015 1175);
FORCEPROP 1 LAST PATH I7
J 0
(-1775 1475);
DISPLAY 0.872340 (-1775 1475);
PAINT PINK (-1775 1475);
DISPLAY INVISIBLE (-1775 1475);
FORCEPROP 2 LAST CDS_SEC 1
J 0
(-1775 1525);
DISPLAY 1.361702 (-1775 1525);
PAINT ORANGE (-1775 1525);
DISPLAY INVISIBLE (-1775 1525);
FORCEPROP 2 LAST $SEC 1
J 0
(-1775 1525);
DISPLAY 0.914894 (-1775 1525);
PAINT MONO (-1775 1525);
DISPLAY INVISIBLE (-1775 1525);
FORCEADD GND..1
(-2350 1125);
FORCEPROP 3 LASTPIN (-2350 1175) SIG_NAME GND\g
J 0
(-2340 1185);
DISPLAY 0.659574 (-2340 1185);
PAINT MONO (-2340 1185);
DISPLAY INVISIBLE (-2340 1185);
FORCEPROP 1 LAST VOLTAGE 0.0V
J 0
(-2395 1082);
DISPLAY 0.340426 (-2395 1082);
PAINT SKYBLUE (-2395 1082);
DISPLAY INVISIBLE (-2395 1082);
FORCEPROP 2 LAST CDS_LIB mstr_symbols
J 0
(-2350 1125);
PAINT ORANGE (-2350 1125);
DISPLAY INVISIBLE (-2350 1125);
FORCEPROP 1 LAST BODY_TYPE PLUMBING
J 0
(-2395 1082);
DISPLAY 0.340426 (-2395 1082);
PAINT GREEN (-2395 1082);
DISPLAY INVISIBLE (-2395 1082);
FORCEPROP 1 LAST HDL_POWER GND
J 0
(-2350 1275);
DISPLAY 1.170213 (-2350 1275);
PAINT GREEN (-2350 1275);
DISPLAY INVISIBLE (-2350 1275);
FORCEPROP 1 LAST SIZE 1B
J 0
(-2275 1075);
DISPLAY 1.170213 (-2275 1075);
PAINT AQUA (-2275 1075);
DISPLAY INVISIBLE (-2275 1075);
FORCEPROP 1 LAST PATH I8
J 0
(-2275 1125);
DISPLAY 0.872340 (-2275 1125);
PAINT AQUA (-2275 1125);
DISPLAY INVISIBLE (-2275 1125);
FORCEADD RCC_DFX1940..1
(-2050 925);
FORCEPROP 2 LASTPIN (-2250 925) $PN 1
J 2
(-2260 935);
DISPLAY 0.617021 (-2260 935);
PAINT ORANGE (-2260 935);
FORCEPROP 1 LAST PACK_TYPE ID4
J 0
(-2200 1000);
DISPLAY 0.617021 (-2200 1000);
PAINT SKYBLUE (-2200 1000);
FORCEPROP 1 LAST LOCATION TC9A1
J 0
(-2200 1050);
DISPLAY 0.617021 (-2200 1050);
PAINT AQUA (-2200 1050);
FORCEPROP 1 LAST MATERIAL EMPTY
J 0
(-2050 1075);
DISPLAY 0.617021 (-2050 1075);
PAINT RED (-2050 1075);
FORCEPROP 2 LASTPIN (-1950 875) $PN 3
J 0
(-1940 885);
DISPLAY 0.617021 (-1940 885);
PAINT ORANGE (-1940 885);
FORCEPROP 2 LASTPIN (-1950 975) $PN 2
J 0
(-1940 985);
DISPLAY 0.617021 (-1940 985);
PAINT ORANGE (-1940 985);
FORCEPROP 2 LAST CDS_LIB mstr_misc
J 0
(-2050 925);
PAINT ORANGE (-2050 925);
DISPLAY INVISIBLE (-2050 925);
FORCEPROP 2 LAST CDS_LOCATION TC9A1
J 0
(-2200 1050);
DISPLAY 0.617021 (-2200 1050);
PAINT AQUA (-2200 1050);
DISPLAY INVISIBLE (-2200 1050);
FORCEPROP 1 LAST PART_NUMBER N_A
J 0
(-1990 775);
DISPLAY 1.170213 (-1990 775);
PAINT BLUE (-1990 775);
DISPLAY INVISIBLE (-1990 775);
FORCEPROP 2 LAST CDS_SEC 1
J 0
(-1750 1125);
DISPLAY 1.361702 (-1750 1125);
PAINT ORANGE (-1750 1125);
DISPLAY INVISIBLE (-1750 1125);
FORCEPROP 2 LAST $SEC 1
J 0
(-1750 1125);
DISPLAY 0.914894 (-1750 1125);
PAINT MONO (-1750 1125);
DISPLAY INVISIBLE (-1750 1125);
FORCEPROP 1 LAST PATH I9
J 0
(-1750 1075);
DISPLAY 0.872340 (-1750 1075);
PAINT PINK (-1750 1075);
DISPLAY INVISIBLE (-1750 1075);
FORCEADD BOM_NOTE..1
(-775 3200);
FORCEPROP 0 LAST L1 WORK LABEL
J 0
(-925 3075);
DISPLAY 1.361702 (-925 3075);
PAINT ORANGE (-925 3075);
FORCEPROP 0 LAST L2 IPN = 622954-001 (MOD FILE)
J 0
(-925 3000);
DISPLAY 1.085106 (-925 3000);
PAINT ORANGE (-925 3000);
FORCEPROP 2 LAST CDS_LIB mstr_symbols
J 0
(-775 3200);
PAINT ORANGE (-775 3200);
DISPLAY INVISIBLE (-775 3200);
FORCEPROP 1 LAST COMMENT_BODY TRUE
J 0
(-750 3300);
DISPLAY 1.319149 (-750 3300);
PAINT ORANGE (-750 3300);
DISPLAY INVISIBLE (-750 3300);
FORCEADD BOM_NOTE..1
(-800 3900);
FORCEPROP 0 LAST L2 IPN = A19177-001 (MOD FILE)
J 0
(-950 3700);
DISPLAY 1.085106 (-950 3700);
PAINT ORANGE (-950 3700);
FORCEPROP 0 LAST L1 PBA / SERIAL NUMBER
J 0
(-950 3775);
DISPLAY 1.361702 (-950 3775);
PAINT ORANGE (-950 3775);
FORCEPROP 2 LAST CDS_LIB mstr_symbols
J 0
(-800 3900);
PAINT ORANGE (-800 3900);
DISPLAY INVISIBLE (-800 3900);
FORCEPROP 1 LAST COMMENT_BODY TRUE
J 0
(-775 4000);
DISPLAY 1.319149 (-775 4000);
PAINT ORANGE (-775 4000);
DISPLAY INVISIBLE (-775 4000);
FORCEADD BOM_NOTE..1
(-800 4600);
FORCEPROP 0 LAST L1 MAC ADDRESS
J 0
(-950 4475);
DISPLAY 1.361702 (-950 4475);
PAINT ORANGE (-950 4475);
FORCEPROP 0 LAST L2 IPN = A19177-001 (MOD FILE)
J 0
(-950 4400);
DISPLAY 1.085106 (-950 4400);
PAINT ORANGE (-950 4400);
FORCEPROP 2 LAST CDS_LIB mstr_symbols
J 0
(-800 4600);
PAINT ORANGE (-800 4600);
DISPLAY INVISIBLE (-800 4600);
FORCEPROP 1 LAST COMMENT_BODY TRUE
J 0
(-775 4700);
DISPLAY 1.319149 (-775 4700);
PAINT ORANGE (-775 4700);
DISPLAY INVISIBLE (-775 4700);
FORCEADD DNS..3
(-420 1345);
PAINT RED (-420 1345);
FORCEPROP 1 LAST COMMENT_BODY TRUE
R 1
J 0
(-345 1120);
DISPLAY 0.872340 (-345 1120);
PAINT GREEN (-345 1120);
DISPLAY INVISIBLE (-345 1120);
FORCEPROP 2 LAST CDS_LIB mstr_misc
J 0
(-420 1345);
PAINT ORANGE (-420 1345);
DISPLAY INVISIBLE (-420 1345);
FORCEADD BOM_NOTE..1
(-800 2025);
FORCEPROP 0 LAST L2 IPN = C48561-001 (MOD FILE)
J 0
(-950 1825);
DISPLAY 1.085106 (-950 1825);
PAINT ORANGE (-950 1825);
FORCEPROP 0 LAST L1 ENGINEERING SAMPLE
J 0
(-950 1900);
DISPLAY 1.361702 (-950 1900);
PAINT ORANGE (-950 1900);
FORCEPROP 2 LAST CDS_LIB mstr_symbols
J 0
(-800 2025);
PAINT ORANGE (-800 2025);
DISPLAY INVISIBLE (-800 2025);
FORCEPROP 1 LAST COMMENT_BODY TRUE
J 0
(-775 2125);
DISPLAY 1.319149 (-775 2125);
PAINT ORANGE (-775 2125);
DISPLAY INVISIBLE (-775 2125);
FORCEADD DNS..2
(-1520 4445);
PAINT RED (-1520 4445);
FORCEPROP 1 LAST COMMENT_BODY TRUE
R 1
J 0
(-1445 4220);
DISPLAY 0.872340 (-1445 4220);
PAINT GREEN (-1445 4220);
DISPLAY INVISIBLE (-1445 4220);
FORCEPROP 2 LAST CDS_LIB mstr_misc
J 0
(-1520 4445);
PAINT ORANGE (-1520 4445);
DISPLAY INVISIBLE (-1520 4445);
FORCEADD DNS..2
(-1520 3795);
PAINT RED (-1520 3795);
FORCEPROP 1 LAST COMMENT_BODY TRUE
R 1
J 0
(-1445 3570);
DISPLAY 0.872340 (-1445 3570);
PAINT GREEN (-1445 3570);
DISPLAY INVISIBLE (-1445 3570);
FORCEPROP 2 LAST CDS_LIB mstr_misc
J 0
(-1520 3795);
PAINT ORANGE (-1520 3795);
DISPLAY INVISIBLE (-1520 3795);
FORCEADD DNS..2
(-1520 3120);
PAINT RED (-1520 3120);
FORCEPROP 1 LAST COMMENT_BODY TRUE
R 1
J 0
(-1445 2895);
DISPLAY 0.872340 (-1445 2895);
PAINT GREEN (-1445 2895);
DISPLAY INVISIBLE (-1445 2895);
FORCEPROP 2 LAST CDS_LIB mstr_misc
J 0
(-1520 3120);
PAINT ORANGE (-1520 3120);
DISPLAY INVISIBLE (-1520 3120);
FORCEADD DNS..2
(-1495 2420);
PAINT RED (-1495 2420);
FORCEPROP 1 LAST COMMENT_BODY TRUE
R 1
J 0
(-1420 2195);
DISPLAY 0.872340 (-1420 2195);
PAINT GREEN (-1420 2195);
DISPLAY INVISIBLE (-1420 2195);
FORCEPROP 2 LAST CDS_LIB mstr_misc
J 0
(-1495 2420);
PAINT ORANGE (-1495 2420);
DISPLAY INVISIBLE (-1495 2420);
FORCEADD DNS..2
(-1520 1895);
PAINT RED (-1520 1895);
FORCEPROP 1 LAST COMMENT_BODY TRUE
R 1
J 0
(-1445 1670);
DISPLAY 0.872340 (-1445 1670);
PAINT GREEN (-1445 1670);
DISPLAY INVISIBLE (-1445 1670);
FORCEPROP 2 LAST CDS_LIB mstr_misc
J 0
(-1520 1895);
PAINT ORANGE (-1520 1895);
DISPLAY INVISIBLE (-1520 1895);
FORCEADD DNS..3
(-395 920);
PAINT RED (-395 920);
FORCEPROP 1 LAST COMMENT_BODY TRUE
R 1
J 0
(-320 695);
DISPLAY 0.872340 (-320 695);
PAINT GREEN (-320 695);
DISPLAY INVISIBLE (-320 695);
FORCEPROP 2 LAST CDS_LIB mstr_misc
J 0
(-395 920);
PAINT ORANGE (-395 920);
DISPLAY INVISIBLE (-395 920);
FORCEADD DNS..3
(-2070 1320);
PAINT RED (-2070 1320);
FORCEPROP 1 LAST COMMENT_BODY TRUE
R 1
J 0
(-1995 1095);
DISPLAY 0.872340 (-1995 1095);
PAINT GREEN (-1995 1095);
DISPLAY INVISIBLE (-1995 1095);
FORCEPROP 2 LAST CDS_LIB mstr_misc
J 0
(-2070 1320);
PAINT ORANGE (-2070 1320);
DISPLAY INVISIBLE (-2070 1320);
FORCEADD BOM_NOTE..1
(-775 2525);
FORCEPROP 0 LAST L1 RE-WORK LABEL
J 0
(-925 2400);
DISPLAY 1.361702 (-925 2400);
PAINT ORANGE (-925 2400);
FORCEPROP 0 LAST L2 IPN = A19177-001 (MOD FILE)
J 0
(-925 2325);
DISPLAY 1.085106 (-925 2325);
PAINT ORANGE (-925 2325);
FORCEPROP 2 LAST CDS_LIB mstr_symbols
J 0
(-775 2525);
PAINT ORANGE (-775 2525);
DISPLAY INVISIBLE (-775 2525);
FORCEPROP 1 LAST COMMENT_BODY TRUE
J 0
(-750 2625);
DISPLAY 1.319149 (-750 2625);
PAINT ORANGE (-750 2625);
DISPLAY INVISIBLE (-750 2625);
FORCEADD DNS..3
(-2045 920);
PAINT RED (-2045 920);
FORCEPROP 1 LAST COMMENT_BODY TRUE
R 1
J 0
(-1970 695);
DISPLAY 0.872340 (-1970 695);
PAINT GREEN (-1970 695);
DISPLAY INVISIBLE (-1970 695);
FORCEPROP 2 LAST CDS_LIB mstr_misc
J 0
(-2045 920);
PAINT ORANGE (-2045 920);
DISPLAY INVISIBLE (-2045 920);
FORCEADD DESIGN_NOTE..1
(-1525 4925);
FORCEPROP 0 LAST L1 LABELS ON BOARD
J 0
(-1225 4925);
DISPLAY 1.361702 (-1225 4925);
PAINT ORANGE (-1225 4925);
FORCEPROP 2 LAST CDS_LIB mstr_symbols
J 0
(-1525 4925);
PAINT ORANGE (-1525 4925);
DISPLAY INVISIBLE (-1525 4925);
FORCEPROP 1 LAST COMMENT_BODY TRUE
J 0
(-1500 5025);
DISPLAY 1.319149 (-1500 5025);
PAINT ORANGE (-1500 5025);
DISPLAY INVISIBLE (-1500 5025);
FORCEADD INTEL_CORP_BPAGE..1
(5350 200);
FORCEPROP 1 LAST CDS_CON_LAST_MODIFIED Tue Dec 01 11:51:54 2015
J 0
(3925 525);
PAINT ORANGE (3925 525);
DISPLAY INVISIBLE (3925 525);
FORCEPROP 1 LAST CUSTOM_TXT_CDS <CURRENT_DESIGN_SHEET> OF <TOTAL_DESIGN_SHEETS>
J 0
(4850 225);
PAINT GREEN (4850 225);
FORCEPROP 1 LAST CUSTOM_TXT_CDS <CON_LAST_MODIFIED>
J 0
(3425 550);
PAINT GREEN (3425 550);
FORCEPROP 2 LAST CUSTOM_TXT_CDS <XR_PAGE_TITLE>
J 0
(-2540 5450);
DISPLAY 0.638298 (-2540 5450);
PAINT PINK (-2540 5450);
DISPLAY INVISIBLE (-2540 5450);
FORCEPROP 1 LAST SCH_TITLE ANCHORS - LABELS
J 0
(-2600 250);
DISPLAY 1.212766 (-2600 250);
PAINT ORANGE (-2600 250);
FORCEPROP 1 LAST SCH_ADDRESS2 P.O. BOX 58119
J 0
(1375 275);
DISPLAY 0.617021 (1375 275);
PAINT GREEN (1375 275);
FORCEPROP 1 LAST SCH_ADDRESS3 Santa Clara, CA 95052-8119
J 0
(1375 225);
DISPLAY 0.617021 (1375 225);
PAINT GREEN (1375 225);
FORCEPROP 1 LAST SCH_ADDRESS1 2200 Mission College Blvd.
J 0
(1375 325);
DISPLAY 0.617021 (1375 325);
PAINT GREEN (1375 325);
FORCEPROP 1 LAST SCH_NUMBER H4694802
J 0
(4050 350);
DISPLAY 1.212766 (4050 350);
PAINT YELLOW (4050 350);
FORCEPROP 1 LAST SCH_DEPT BESD
J 1
(900 300);
DISPLAY 1.212766 (900 300);
PAINT YELLOW (900 300);
FORCEPROP 1 LAST SCH_REV 2.420
J 0
(5100 350);
DISPLAY 0.978723 (5100 350);
PAINT YELLOW (5100 350);
FORCEPROP 2 LAST PAGE_BORDER TRUE
J 0
(-2540 5450);
DISPLAY 0.638298 (-2540 5450);
PAINT PINK (-2540 5450);
DISPLAY INVISIBLE (-2540 5450);
FORCEPROP 1 LAST COMMENT_BODY TRUE
J 0
(5362 212);
DISPLAY 0.468085 (5362 212);
PAINT GREEN (5362 212);
DISPLAY INVISIBLE (5362 212);
FORCEPROP 2 LAST CDS_LIB mstr_symbols
J 0
(5350 200);
PAINT MONO (5350 200);
DISPLAY INVISIBLE (5350 200);
FORCEPROP 2 LAST CDS_XR_PAGE_TITLE CR-110 : @BASEBOARD_FAB2_LIB.BASEBOARD_FAB2(SCH_1):PAGE110
J 0
(-2540 5450);
DISPLAY 0.638298 (-2540 5450);
PAINT PINK (-2540 5450);
DISPLAY INVISIBLE (-2540 5450);
WIRE 16 -1 (-2350 925)(-2250 925);
WIRE 16 -1 (-2350 800)(-2350 925);
WIRE 16 -1 (-675 1350)(-625 1350);
WIRE 16 -1 (-675 1200)(-675 1350);
WIRE 16 -1 (-675 925)(-600 925);
WIRE 16 -1 (-675 800)(-675 925);
WIRE 16 -1 (-2350 1325)(-2275 1325);
WIRE 16 -1 (-2350 1175)(-2350 1325);
WIRE 16 273 (1125 5150)(1125 550);
WIRE 16 -1 (600 975)(600 875);
WIRE 16 -1 (-300 975)(600 975);
FORCEPROP 2 LAST SIG_NAME RCC_DFX_1940_4
J 0
(-85 985);
DISPLAY 0.617021 (-85 985);
PAINT ORANGE (-85 985);
FORCEPROP 2 LASTPROP $XRERR UNIQUE?
J 0
(-325 985);
DISPLAY 0.638298 (-325 985);
PAINT MONO (-325 985);
DISPLAY INVISIBLE (-325 985);
WIRE 16 -1 (600 875)(-300 875);
WIRE 16 -1 (575 1400)(575 1300);
WIRE 16 -1 (-325 1400)(575 1400);
FORCEPROP 2 LAST SIG_NAME RCC_DFX_1940_3
J 0
(-110 1410);
DISPLAY 0.617021 (-110 1410);
PAINT ORANGE (-110 1410);
FORCEPROP 2 LASTPROP $XRERR UNIQUE?
J 0
(-350 1410);
DISPLAY 0.638298 (-350 1410);
PAINT MONO (-350 1410);
DISPLAY INVISIBLE (-350 1410);
WIRE 16 -1 (575 1300)(-325 1300);
WIRE 16 273 (-2475 1625)(975 1625);
WIRE 16 -1 (-1150 1375)(-1150 1275);
WIRE 16 -1 (-1975 1375)(-1150 1375);
FORCEPROP 2 LAST SIG_NAME RCC_DFX_1940_1
J 0
(-1835 1385);
DISPLAY 0.617021 (-1835 1385);
PAINT ORANGE (-1835 1385);
FORCEPROP 2 LASTPROP $XRERR UNIQUE?
J 0
(-2075 1385);
DISPLAY 0.638298 (-2075 1385);
PAINT MONO (-2075 1385);
DISPLAY INVISIBLE (-2075 1385);
WIRE 16 -1 (-1150 1275)(-1975 1275);
WIRE 16 -1 (-1125 975)(-1125 875);
WIRE 16 -1 (-1950 975)(-1125 975);
FORCEPROP 2 LAST SIG_NAME RCC_DFX_1940_2
J 0
(-1835 985);
DISPLAY 0.617021 (-1835 985);
PAINT ORANGE (-1835 985);
FORCEPROP 2 LASTPROP $XRERR UNIQUE?
J 0
(-2075 985);
DISPLAY 0.638298 (-2075 985);
PAINT MONO (-2075 985);
DISPLAY INVISIBLE (-2075 985);
WIRE 16 -1 (-1125 875)(-1950 875);
FORCENOTE
ROOM=LABELS
(-2525 600) 0;
DISPLAY LEFT (-2525 600);
DISPLAY 1.021277 (-2525 600);
PAINT PURPLE (-2525 600);
FORCENOTE
BOM_COST=TEST_MFG
(-2525 525) 0;
DISPLAY LEFT (-2525 525);
DISPLAY 1.021277 (-2525 525);
PAINT PURPLE (-2525 525);
QUIT
